(kicad_pcb
	(version 20260206)
	(generator "pcbnew")
	(generator_version "10.0")
	(general
		(thickness 1.6)
		(legacy_teardrops no)
	)
	(paper "A4")
	(title_block
		(title "03242023_DA0F0TMBIJ0_F0T_Motherboard_J_brd_V01_OCP.brd")
		(comment 1 "Grand Teton / footprints 5968-5973 of 6105")
	)
	(layers
		(0 "F.Cu" signal "TOP")
		(4 "In1.Cu" signal "GND")
		(6 "In2.Cu" signal "IN1")
		(8 "In3.Cu" signal "GND1")
		(10 "In4.Cu" signal "IN2")
		(12 "In5.Cu" signal "GND2")
		(14 "In6.Cu" signal "IN3")
		(16 "In7.Cu" signal "GND3")
		(18 "In8.Cu" signal "VCC")
		(20 "In9.Cu" signal "VCC1")
		(22 "In10.Cu" signal "GND4")
		(24 "In11.Cu" signal "IN4")
		(26 "In12.Cu" signal "GND5")
		(28 "In13.Cu" signal "IN5")
		(30 "In14.Cu" signal "GND6")
		(32 "In15.Cu" signal "IN6")
		(34 "In16.Cu" signal "GND7")
		(2 "B.Cu" signal "BOTTOM")
		(9 "F.Adhes" user "F.Adhesive")
		(11 "B.Adhes" user "B.Adhesive")
		(13 "F.Paste" user "Package Geometry/Pastemask Top")
		(15 "B.Paste" user "Package Geometry/Pastemask Bottom")
		(5 "F.SilkS" user "Ref Des/Silkscreen Top")
		(7 "B.SilkS" user "Ref Des/Silkscreen Bottom")
		(1 "F.Mask" user "Board Geometry/Soldermask Top")
		(3 "B.Mask" user "Board Geometry/Soldermask Bottom")
		(17 "Dwgs.User" user "User.Drawings")
		(19 "Cmts.User" user "User.Comments")
		(21 "Eco1.User" user "User.Eco1")
		(23 "Eco2.User" user "User.Eco2")
		(25 "Edge.Cuts" user "Board Geometry/Outline")
		(27 "Margin" user)
		(31 "F.CrtYd" user "Package Geometry/Place Bound Top")
		(29 "B.CrtYd" user "Package Geometry/Place Bound Bottom")
		(35 "F.Fab" user "Ref Des/Assembly Top")
		(33 "B.Fab" user "Ref Des/Assembly Bottom")
	)
	(footprint ""
		(layer "B.Cu")
		(at 302.151542 -50.923444 180)
		(property "Reference" "C1244"
			(at 0 0 0)
			(layer "B.SilkS")
			(hide yes)
			(effects
				(font
					(size 1.27 1.27)
				)
				(justify mirror)
			)
		)
		(property "Value" ""
			(at 0 0 0)
			(layer "B.Fab")
			(effects
				(font
					(size 1.27 1.27)
				)
				(justify mirror)
			)
		)
		(duplicate_pad_numbers_are_jumpers no)
		(fp_line
			(start 1.524 0.762)
			(end 1.524 -0.762)
			(stroke
				(width 0.1524)
				(type default)
			)
			(layer "B.SilkS")
		)
		(fp_line
			(start 1.524 -0.762)
			(end -1.524 -0.762)
			(stroke
				(width 0.1524)
				(type default)
			)
			(layer "B.SilkS")
		)
		(fp_line
			(start -1.524 0.762)
			(end 1.524 0.762)
			(stroke
				(width 0.1524)
				(type default)
			)
			(layer "B.SilkS")
		)
		(fp_line
			(start -1.524 -0.762)
			(end -1.524 0.762)
			(stroke
				(width 0.1524)
				(type default)
			)
			(layer "B.SilkS")
		)
		(fp_line
			(start 1.1049 0.724916)
			(end -1.1049 0.724916)
			(stroke
				(width 0.1)
				(type default)
			)
			(layer "B.Fab")
		)
		(fp_line
			(start 1.1049 -0.724916)
			(end 1.1049 0.724916)
			(stroke
				(width 0.1)
				(type default)
			)
			(layer "B.Fab")
		)
		(fp_line
			(start -1.1049 0.724916)
			(end -1.1049 -0.724916)
			(stroke
				(width 0.1)
				(type default)
			)
			(layer "B.Fab")
		)
		(fp_line
			(start -1.1049 -0.724916)
			(end 1.1049 -0.724916)
			(stroke
				(width 0.1)
				(type default)
			)
			(layer "B.Fab")
		)
		(pad "1" smd rect
			(at 0.889 0 180)
			(size 1.016 1.27)
			(layers "B.Cu" "B.Mask" "B.Paste")
			(net "P1V05_PCH_AUX")
		)
		(pad "2" smd rect
			(at -0.889 0 180)
			(size 1.016 1.27)
			(layers "B.Cu" "B.Mask" "B.Paste")
			(net "GND")
		)
	)
	(footprint ""
		(layer "B.Cu")
		(at 254.268986 -86.824566)
		(property "Reference" "R1471"
			(at 0 0 0)
			(layer "B.SilkS")
			(hide yes)
			(effects
				(font
					(size 1.27 1.27)
				)
				(justify mirror)
			)
		)
		(property "Value" ""
			(at 0 0 0)
			(layer "B.Fab")
			(effects
				(font
					(size 1.27 1.27)
				)
				(justify mirror)
			)
		)
		(duplicate_pad_numbers_are_jumpers no)
		(fp_line
			(start -0.7874 -0.4064)
			(end -0.7874 0.4064)
			(stroke
				(width 0.1524)
				(type default)
			)
			(layer "B.SilkS")
		)
		(fp_line
			(start -0.7874 0.4064)
			(end 0.7874 0.4064)
			(stroke
				(width 0.1524)
				(type default)
			)
			(layer "B.SilkS")
		)
		(fp_line
			(start 0.7874 -0.4064)
			(end -0.7874 -0.4064)
			(stroke
				(width 0.1524)
				(type default)
			)
			(layer "B.SilkS")
		)
		(fp_line
			(start 0.7874 0.4064)
			(end 0.7874 -0.4064)
			(stroke
				(width 0.1524)
				(type default)
			)
			(layer "B.SilkS")
		)
		(fp_line
			(start -0.67945 -0.3048)
			(end -0.67945 0.3048)
			(stroke
				(width 0.1)
				(type default)
			)
			(layer "B.Fab")
		)
		(fp_line
			(start -0.67945 0.3048)
			(end -0.120396 0.3048)
			(stroke
				(width 0.1)
				(type default)
			)
			(layer "B.Fab")
		)
		(fp_line
			(start -0.12065 -0.3048)
			(end -0.67945 -0.3048)
			(stroke
				(width 0.1)
				(type default)
			)
			(layer "B.Fab")
		)
		(fp_line
			(start -0.12065 -0.2794)
			(end -0.12065 -0.3048)
			(stroke
				(width 0.1)
				(type default)
			)
			(layer "B.Fab")
		)
		(fp_line
			(start -0.120396 0.2794)
			(end 0.12065 0.2794)
			(stroke
				(width 0.1)
				(type default)
			)
			(layer "B.Fab")
		)
		(fp_line
			(start -0.120396 0.3048)
			(end -0.120396 0.2794)
			(stroke
				(width 0.1)
				(type default)
			)
			(layer "B.Fab")
		)
		(fp_line
			(start 0.12065 -0.305054)
			(end 0.12065 -0.2794)
			(stroke
				(width 0.1)
				(type default)
			)
			(layer "B.Fab")
		)
		(fp_line
			(start 0.12065 -0.2794)
			(end -0.12065 -0.2794)
			(stroke
				(width 0.1)
				(type default)
			)
			(layer "B.Fab")
		)
		(fp_line
			(start 0.12065 0.2794)
			(end 0.12065 0.3048)
			(stroke
				(width 0.1)
				(type default)
			)
			(layer "B.Fab")
		)
		(fp_line
			(start 0.12065 0.3048)
			(end 0.67945 0.3048)
			(stroke
				(width 0.1)
				(type default)
			)
			(layer "B.Fab")
		)
		(fp_line
			(start 0.67945 -0.305054)
			(end 0.12065 -0.305054)
			(stroke
				(width 0.1)
				(type default)
			)
			(layer "B.Fab")
		)
		(fp_line
			(start 0.67945 0.3048)
			(end 0.67945 -0.305054)
			(stroke
				(width 0.1)
				(type default)
			)
			(layer "B.Fab")
		)
		(pad "1" smd circle
			(at 0.40005 0 180)
			(size 0 0)
			(layers "B.Cu" "B.Mask" "B.Paste")
			(net "P3V3_AUX")
		)
		(pad "2" smd circle
			(at -0.40005 0 180)
			(size 0 0)
			(layers "B.Cu" "B.Mask" "B.Paste")
			(net "FM_CLK_CK440_SS_EN")
		)
	)
	(footprint ""
		(layer "B.Cu")
		(at 312.090816 -27.320748 -90)
		(property "Reference" "C1209"
			(at 0 0 90)
			(layer "B.SilkS")
			(hide yes)
			(effects
				(font
					(size 1.27 1.27)
				)
				(justify mirror)
			)
		)
		(property "Value" ""
			(at 0 0 90)
			(layer "B.Fab")
			(effects
				(font
					(size 1.27 1.27)
				)
				(justify mirror)
			)
		)
		(duplicate_pad_numbers_are_jumpers no)
		(fp_line
			(start -0.7874 0.4064)
			(end 0.7874 0.4064)
			(stroke
				(width 0.1524)
				(type default)
			)
			(layer "B.SilkS")
		)
		(fp_line
			(start 0.7874 0.4064)
			(end 0.7874 -0.4064)
			(stroke
				(width 0.1524)
				(type default)
			)
			(layer "B.SilkS")
		)
		(fp_line
			(start -0.7874 -0.4064)
			(end -0.7874 0.4064)
			(stroke
				(width 0.1524)
				(type default)
			)
			(layer "B.SilkS")
		)
		(fp_line
			(start 0.7874 -0.4064)
			(end -0.7874 -0.4064)
			(stroke
				(width 0.1524)
				(type default)
			)
			(layer "B.SilkS")
		)
		(fp_line
			(start -0.67945 0.3048)
			(end -0.120396 0.3048)
			(stroke
				(width 0.1)
				(type default)
			)
			(layer "B.Fab")
		)
		(fp_line
			(start -0.120396 0.3048)
			(end -0.120396 0.2794)
			(stroke
				(width 0.1)
				(type default)
			)
			(layer "B.Fab")
		)
		(fp_line
			(start 0.12065 0.3048)
			(end 0.67945 0.3048)
			(stroke
				(width 0.1)
				(type default)
			)
			(layer "B.Fab")
		)
		(fp_line
			(start 0.67945 0.3048)
			(end 0.67945 -0.305054)
			(stroke
				(width 0.1)
				(type default)
			)
			(layer "B.Fab")
		)
		(fp_line
			(start -0.120396 0.2794)
			(end 0.12065 0.2794)
			(stroke
				(width 0.1)
				(type default)
			)
			(layer "B.Fab")
		)
		(fp_line
			(start 0.12065 0.2794)
			(end 0.12065 0.3048)
			(stroke
				(width 0.1)
				(type default)
			)
			(layer "B.Fab")
		)
		(fp_line
			(start -0.12065 -0.2794)
			(end -0.12065 -0.3048)
			(stroke
				(width 0.1)
				(type default)
			)
			(layer "B.Fab")
		)
		(fp_line
			(start 0.12065 -0.2794)
			(end -0.12065 -0.2794)
			(stroke
				(width 0.1)
				(type default)
			)
			(layer "B.Fab")
		)
		(fp_line
			(start -0.67945 -0.3048)
			(end -0.67945 0.3048)
			(stroke
				(width 0.1)
				(type default)
			)
			(layer "B.Fab")
		)
		(fp_line
			(start -0.12065 -0.3048)
			(end -0.67945 -0.3048)
			(stroke
				(width 0.1)
				(type default)
			)
			(layer "B.Fab")
		)
		(fp_line
			(start 0.12065 -0.305054)
			(end 0.12065 -0.2794)
			(stroke
				(width 0.1)
				(type default)
			)
			(layer "B.Fab")
		)
		(fp_line
			(start 0.67945 -0.305054)
			(end 0.12065 -0.305054)
			(stroke
				(width 0.1)
				(type default)
			)
			(layer "B.Fab")
		)
		(pad "1" smd circle
			(at 0.40005 0 90)
			(size 0 0)
			(layers "B.Cu" "B.Mask" "B.Paste")
			(net "PWRGD_SYS_PWROK_R")
		)
		(pad "2" smd circle
			(at -0.40005 0 90)
			(size 0 0)
			(layers "B.Cu" "B.Mask" "B.Paste")
			(net "GND")
		)
	)
	(footprint ""
		(layer "B.Cu")
		(at 93.571314 -336.278474 -90)
		(property "Reference" "PR330"
			(at 0 0 90)
			(layer "B.SilkS")
			(hide yes)
			(effects
				(font
					(size 1.27 1.27)
				)
				(justify mirror)
			)
		)
		(property "Value" ""
			(at 0 0 90)
			(layer "B.Fab")
			(effects
				(font
					(size 1.27 1.27)
				)
				(justify mirror)
			)
		)
		(duplicate_pad_numbers_are_jumpers no)
		(fp_line
			(start -0.7874 0.4064)
			(end 0.7874 0.4064)
			(stroke
				(width 0.1524)
				(type default)
			)
			(layer "B.SilkS")
		)
		(fp_line
			(start 0.7874 0.4064)
			(end 0.7874 -0.4064)
			(stroke
				(width 0.1524)
				(type default)
			)
			(layer "B.SilkS")
		)
		(fp_line
			(start -0.7874 -0.4064)
			(end -0.7874 0.4064)
			(stroke
				(width 0.1524)
				(type default)
			)
			(layer "B.SilkS")
		)
		(fp_line
			(start 0.7874 -0.4064)
			(end -0.7874 -0.4064)
			(stroke
				(width 0.1524)
				(type default)
			)
			(layer "B.SilkS")
		)
		(fp_line
			(start -0.67945 0.3048)
			(end -0.120396 0.3048)
			(stroke
				(width 0.1)
				(type default)
			)
			(layer "B.Fab")
		)
		(fp_line
			(start -0.120396 0.3048)
			(end -0.120396 0.2794)
			(stroke
				(width 0.1)
				(type default)
			)
			(layer "B.Fab")
		)
		(fp_line
			(start 0.12065 0.3048)
			(end 0.67945 0.3048)
			(stroke
				(width 0.1)
				(type default)
			)
			(layer "B.Fab")
		)
		(fp_line
			(start 0.67945 0.3048)
			(end 0.67945 -0.305054)
			(stroke
				(width 0.1)
				(type default)
			)
			(layer "B.Fab")
		)
		(fp_line
			(start -0.120396 0.2794)
			(end 0.12065 0.2794)
			(stroke
				(width 0.1)
				(type default)
			)
			(layer "B.Fab")
		)
		(fp_line
			(start 0.12065 0.2794)
			(end 0.12065 0.3048)
			(stroke
				(width 0.1)
				(type default)
			)
			(layer "B.Fab")
		)
		(fp_line
			(start -0.12065 -0.2794)
			(end -0.12065 -0.3048)
			(stroke
				(width 0.1)
				(type default)
			)
			(layer "B.Fab")
		)
		(fp_line
			(start 0.12065 -0.2794)
			(end -0.12065 -0.2794)
			(stroke
				(width 0.1)
				(type default)
			)
			(layer "B.Fab")
		)
		(fp_line
			(start -0.67945 -0.3048)
			(end -0.67945 0.3048)
			(stroke
				(width 0.1)
				(type default)
			)
			(layer "B.Fab")
		)
		(fp_line
			(start -0.12065 -0.3048)
			(end -0.67945 -0.3048)
			(stroke
				(width 0.1)
				(type default)
			)
			(layer "B.Fab")
		)
		(fp_line
			(start 0.12065 -0.305054)
			(end 0.12065 -0.2794)
			(stroke
				(width 0.1)
				(type default)
			)
			(layer "B.Fab")
		)
		(fp_line
			(start 0.67945 -0.305054)
			(end 0.12065 -0.305054)
			(stroke
				(width 0.1)
				(type default)
			)
			(layer "B.Fab")
		)
		(pad "1" smd circle
			(at 0.40005 0 90)
			(size 0 0)
			(layers "B.Cu" "B.Mask" "B.Paste")
			(net "PVCCIN_CPU1_VOS1")
		)
		(pad "2" smd circle
			(at -0.40005 0 90)
			(size 0 0)
			(layers "B.Cu" "B.Mask" "B.Paste")
			(net "PVCCIN_CPU1")
		)
	)
	(footprint ""
		(layer "B.Cu")
		(at 29.577538 -167.0177)
		(property "Reference" "PR218"
			(at 0 0 0)
			(layer "B.SilkS")
			(hide yes)
			(effects
				(font
					(size 1.27 1.27)
				)
				(justify mirror)
			)
		)
		(property "Value" ""
			(at 0 0 0)
			(layer "B.Fab")
			(effects
				(font
					(size 1.27 1.27)
				)
				(justify mirror)
			)
		)
		(duplicate_pad_numbers_are_jumpers no)
		(fp_line
			(start -0.7874 -0.4064)
			(end -0.7874 0.4064)
			(stroke
				(width 0.1524)
				(type default)
			)
			(layer "B.SilkS")
		)
		(fp_line
			(start -0.7874 0.4064)
			(end 0.7874 0.4064)
			(stroke
				(width 0.1524)
				(type default)
			)
			(layer "B.SilkS")
		)
		(fp_line
			(start 0.7874 -0.4064)
			(end -0.7874 -0.4064)
			(stroke
				(width 0.1524)
				(type default)
			)
			(layer "B.SilkS")
		)
		(fp_line
			(start 0.7874 0.4064)
			(end 0.7874 -0.4064)
			(stroke
				(width 0.1524)
				(type default)
			)
			(layer "B.SilkS")
		)
		(fp_line
			(start -0.67945 -0.3048)
			(end -0.67945 0.3048)
			(stroke
				(width 0.1)
				(type default)
			)
			(layer "B.Fab")
		)
		(fp_line
			(start -0.67945 0.3048)
			(end -0.120396 0.3048)
			(stroke
				(width 0.1)
				(type default)
			)
			(layer "B.Fab")
		)
		(fp_line
			(start -0.12065 -0.3048)
			(end -0.67945 -0.3048)
			(stroke
				(width 0.1)
				(type default)
			)
			(layer "B.Fab")
		)
		(fp_line
			(start -0.12065 -0.2794)
			(end -0.12065 -0.3048)
			(stroke
				(width 0.1)
				(type default)
			)
			(layer "B.Fab")
		)
		(fp_line
			(start -0.120396 0.2794)
			(end 0.12065 0.2794)
			(stroke
				(width 0.1)
				(type default)
			)
			(layer "B.Fab")
		)
		(fp_line
			(start -0.120396 0.3048)
			(end -0.120396 0.2794)
			(stroke
				(width 0.1)
				(type default)
			)
			(layer "B.Fab")
		)
		(fp_line
			(start 0.12065 -0.305054)
			(end 0.12065 -0.2794)
			(stroke
				(width 0.1)
				(type default)
			)
			(layer "B.Fab")
		)
		(fp_line
			(start 0.12065 -0.2794)
			(end -0.12065 -0.2794)
			(stroke
				(width 0.1)
				(type default)
			)
			(layer "B.Fab")
		)
		(fp_line
			(start 0.12065 0.2794)
			(end 0.12065 0.3048)
			(stroke
				(width 0.1)
				(type default)
			)
			(layer "B.Fab")
		)
		(fp_line
			(start 0.12065 0.3048)
			(end 0.67945 0.3048)
			(stroke
				(width 0.1)
				(type default)
			)
			(layer "B.Fab")
		)
		(fp_line
			(start 0.67945 -0.305054)
			(end 0.12065 -0.305054)
			(stroke
				(width 0.1)
				(type default)
			)
			(layer "B.Fab")
		)
		(fp_line
			(start 0.67945 0.3048)
			(end 0.67945 -0.305054)
			(stroke
				(width 0.1)
				(type default)
			)
			(layer "B.Fab")
		)
		(pad "1" smd circle
			(at 0.40005 0 180)
			(size 0 0)
			(layers "B.Cu" "B.Mask" "B.Paste")
			(net "PVCCD_HV_CPU1_ISENSE_N")
		)
		(pad "2" smd circle
			(at -0.40005 0 180)
			(size 0 0)
			(layers "B.Cu" "B.Mask" "B.Paste")
			(net "GND")
		)
	)
	(footprint ""
		(layer "B.Cu")
		(at 179.63388 -125.313948)
		(property "Reference" "R3458"
			(at 0 0 0)
			(layer "B.SilkS")
			(hide yes)
			(effects
				(font
					(size 1.27 1.27)
				)
				(justify mirror)
			)
		)
		(property "Value" ""
			(at 0 0 0)
			(layer "B.Fab")
			(effects
				(font
					(size 1.27 1.27)
				)
				(justify mirror)
			)
		)
		(duplicate_pad_numbers_are_jumpers no)
		(fp_line
			(start -1.2954 -0.5842)
			(end -1.2954 0.5842)
			(stroke
				(width 0.1524)
				(type default)
			)
			(layer "B.SilkS")
		)
		(fp_line
			(start -1.2954 0.5842)
			(end 1.2954 0.5842)
			(stroke
				(width 0.1524)
				(type default)
			)
			(layer "B.SilkS")
		)
		(fp_line
			(start 1.2954 -0.5842)
			(end -1.2954 -0.5842)
			(stroke
				(width 0.1524)
				(type default)
			)
			(layer "B.SilkS")
		)
		(fp_line
			(start 1.2954 0.5842)
			(end 1.2954 -0.5842)
			(stroke
				(width 0.1524)
				(type default)
			)
			(layer "B.SilkS")
		)
		(fp_line
			(start -1.1938 -0.406654)
			(end -1.1938 0.4064)
			(stroke
				(width 0.1)
				(type default)
			)
			(layer "B.Fab")
		)
		(fp_line
			(start -1.1938 0.4064)
			(end -0.8636 0.4064)
			(stroke
				(width 0.1)
				(type default)
			)
			(layer "B.Fab")
		)
		(fp_line
			(start -0.8636 -0.4572)
			(end -0.8636 -0.406654)
			(stroke
				(width 0.1)
				(type default)
			)
			(layer "B.Fab")
		)
		(fp_line
			(start -0.8636 -0.406654)
			(end -1.1938 -0.406654)
			(stroke
				(width 0.1)
				(type default)
			)
			(layer "B.Fab")
		)
		(fp_line
			(start -0.8636 0.4064)
			(end -0.8636 0.4572)
			(stroke
				(width 0.1)
				(type default)
			)
			(layer "B.Fab")
		)
		(fp_line
			(start -0.8636 0.4572)
			(end 0.8636 0.4572)
			(stroke
				(width 0.1)
				(type default)
			)
			(layer "B.Fab")
		)
		(fp_line
			(start 0.8636 -0.4572)
			(end -0.8636 -0.4572)
			(stroke
				(width 0.1)
				(type default)
			)
			(layer "B.Fab")
		)
		(fp_line
			(start 0.8636 -0.406654)
			(end 0.8636 -0.4572)
			(stroke
				(width 0.1)
				(type default)
			)
			(layer "B.Fab")
		)
		(fp_line
			(start 0.8636 0.4064)
			(end 1.1938 0.4064)
			(stroke
				(width 0.1)
				(type default)
			)
			(layer "B.Fab")
		)
		(fp_line
			(start 0.8636 0.4318)
			(end 0.8636 0.4064)
			(stroke
				(width 0.1)
				(type default)
			)
			(layer "B.Fab")
		)
		(fp_line
			(start 0.8636 0.4572)
			(end 0.8636 0.4318)
			(stroke
				(width 0.1)
				(type default)
			)
			(layer "B.Fab")
		)
		(fp_line
			(start 1.1938 -0.406654)
			(end 0.8636 -0.406654)
			(stroke
				(width 0.1)
				(type default)
			)
			(layer "B.Fab")
		)
		(fp_line
			(start 1.1938 0.4064)
			(end 1.1938 -0.406654)
			(stroke
				(width 0.1)
				(type default)
			)
			(layer "B.Fab")
		)
		(pad "1" smd rect
			(at 0.7366 0 270)
			(size 0.7112 0.8128)
			(layers "B.Cu" "B.Mask" "B.Paste")
			(net "P3V3_AUX")
		)
		(pad "2" smd rect
			(at -0.7366 0 270)
			(size 0.7112 0.8128)
			(layers "B.Cu" "B.Mask" "B.Paste")
			(net "VCC_PLD_CORE")
		)
	)
)
